# BASEBOARD_FAB2 (Tioga Pass) — schematic netlist excerpt (pin names and nets, part order shuffled) for the footprints in the layout excerpt that follows; sources: Cadence DE-HDL packaged netlist, KiCad conversion of Wiwynn_Tioga_Pass_MB.brd

C2D6  CAP_A  22.0UF 4V 20% X6S  pkg 0603V  page 228 : A = PVDDQ_KLM ; B = GND
R9F28  RES  221 1.0% CHIP  pkg 0402  page 177 : A = P3V3_STBY ; B = FM_RED_LED_ANODE
R4D60  RES  100.0K 1% CHIP  pkg 0402  page 213 : A = VR_FET_SW_P12V_STBY_PVCCIN_CPU0 ; B = VR_PVCCIO_CPU1_VINSEN

(kicad_pcb
	(version 20260206)
	(generator "pcbnew")
	(generator_version "10.0")
	(general
		(thickness 1.6)
		(legacy_teardrops no)
	)
	(paper "A4")
	(title_block
		(title "Wiwynn_Tioga_Pass_MB.brd")
		(comment 1 "Tioga Pass / footprints 963-965 of 4770")
	)
	(layers
		(0 "F.Cu" signal "TOP")
		(4 "In1.Cu" signal "L2GND")
		(6 "In2.Cu" signal "L3")
		(8 "In3.Cu" signal "L4GND")
		(10 "In4.Cu" signal "L5")
		(12 "In5.Cu" signal "L6GND")
		(14 "In6.Cu" signal "L7VCC")
		(16 "In7.Cu" signal "L8VCC")
		(18 "In8.Cu" signal "L9GND")
		(20 "In9.Cu" signal "L10")
		(22 "In10.Cu" signal "L11GND")
		(24 "In11.Cu" signal "L12")
		(26 "In12.Cu" signal "L13GND")
		(2 "B.Cu" signal "BOTTOM")
		(9 "F.Adhes" user "F.Adhesive")
		(11 "B.Adhes" user "B.Adhesive")
		(13 "F.Paste" user "Package Geometry/Pastemask Top")
		(15 "B.Paste" user "Package Geometry/Pastemask Bottom")
		(5 "F.SilkS" user "Ref Des/Silkscreen Top")
		(7 "B.SilkS" user "Ref Des/Silkscreen Bottom")
		(1 "F.Mask" user "Board Geometry/Soldermask Top")
		(3 "B.Mask" user "Board Geometry/Soldermask Bottom")
		(17 "Dwgs.User" user "User.Drawings")
		(19 "Cmts.User" user "User.Comments")
		(21 "Eco1.User" user "User.Eco1")
		(23 "Eco2.User" user "User.Eco2")
		(25 "Edge.Cuts" user "Board Geometry/Outline")
		(27 "Margin" user)
		(31 "F.CrtYd" user "Package Geometry/Place Bound Top")
		(29 "B.CrtYd" user "Package Geometry/Place Bound Bottom")
		(35 "F.Fab" user "Ref Des/Assembly Top")
		(33 "B.Fab" user "Ref Des/Assembly Bottom")
	)
	(footprint ""
		(layer "F.Cu")
		(at 174.6377 -66.191638 -90)
		(property "Reference" "R4D60"
			(at 0 0 270)
			(layer "F.SilkS")
			(hide yes)
			(effects
				(font
					(size 1.27 1.27)
				)
			)
		)
		(property "Value" ""
			(at 0 0 270)
			(layer "F.Fab")
			(effects
				(font
					(size 1.27 1.27)
				)
			)
		)
		(duplicate_pad_numbers_are_jumpers no)
		(fp_poly
			(pts
				(xy -0.2794 -0.1016) (xy 0.2794 -0.1016) (xy 0.2794 0.9906) (xy -0.2794 0.9906)
			)
			(stroke
				(width 0)
				(type default)
			)
			(fill no)
			(layer "F.CrtYd")
		)
		(fp_line
			(start -0.2794 0.9906)
			(end 0.2794 0.9906)
			(stroke
				(width 0.1)
				(type default)
			)
			(layer "F.Fab")
		)
		(fp_line
			(start 0.2794 0.9906)
			(end 0.2794 -0.1016)
			(stroke
				(width 0.1)
				(type default)
			)
			(layer "F.Fab")
		)
		(fp_line
			(start -0.2794 -0.1016)
			(end -0.2794 0.9906)
			(stroke
				(width 0.1)
				(type default)
			)
			(layer "F.Fab")
		)
		(fp_line
			(start 0.2794 -0.1016)
			(end -0.2794 -0.1016)
			(stroke
				(width 0.1)
				(type default)
			)
			(layer "F.Fab")
		)
		(pad "1" smd rect
			(at 0 0 270)
			(size 0.508 0.508)
			(layers "F.Cu" "F.Mask" "F.Paste")
			(net "VR_FET_SW_P12V_STBY_PVCCIN_CPU0")
		)
		(pad "2" smd rect
			(at 0 0.889 270)
			(size 0.508 0.508)
			(layers "F.Cu" "F.Mask" "F.Paste")
			(net "VR_PVCCIO_CPU1_VINSEN")
		)
		(zone
			(layer "F.Cu")
			(hatch none 0.5)
			(connect_pads
				(clearance 0)
			)
			(min_thickness 0.25)
			(keepout
				(tracks not_allowed)
				(vias allowed)
				(pads allowed)
				(copperpour not_allowed)
				(footprints allowed)
			)
			(placement
				(enabled no)
				(sheetname "")
			)
			(fill
				(thermal_gap 0.5)
				(thermal_bridge_width 0.5)
				(island_removal_mode 0)
			)
			(polygon
				(pts
					(xy 174.0027 -66.445638) (xy 174.0027 -65.937638) (xy 174.3837 -65.937638) (xy 174.3837 -66.445638)
				)
			)
		)
		(zone
			(layer "F.Cu")
			(hatch none 0.5)
			(connect_pads
				(clearance 0)
			)
			(min_thickness 0.25)
			(keepout
				(tracks allowed)
				(vias not_allowed)
				(pads allowed)
				(copperpour not_allowed)
				(footprints allowed)
			)
			(placement
				(enabled no)
				(sheetname "")
			)
			(fill
				(thermal_gap 0.5)
				(thermal_bridge_width 0.5)
				(island_removal_mode 0)
			)
			(polygon
				(pts
					(xy 174.3837 -66.445638) (xy 174.3837 -65.937638) (xy 174.0027 -65.937638) (xy 174.0027 -66.445638)
				)
			)
		)
	)
	(footprint ""
		(layer "F.Cu")
		(at 455.6125 -30.48 -90)
		(property "Reference" "R9F28"
			(at 0 0 270)
			(layer "F.SilkS")
			(hide yes)
			(effects
				(font
					(size 1.27 1.27)
				)
			)
		)
		(property "Value" ""
			(at 0 0 270)
			(layer "F.Fab")
			(effects
				(font
					(size 1.27 1.27)
				)
			)
		)
		(duplicate_pad_numbers_are_jumpers no)
		(fp_poly
			(pts
				(xy -0.2794 -0.1016) (xy 0.2794 -0.1016) (xy 0.2794 0.9906) (xy -0.2794 0.9906)
			)
			(stroke
				(width 0)
				(type default)
			)
			(fill no)
			(layer "F.CrtYd")
		)
		(fp_line
			(start -0.2794 0.9906)
			(end 0.2794 0.9906)
			(stroke
				(width 0.1)
				(type default)
			)
			(layer "F.Fab")
		)
		(fp_line
			(start 0.2794 0.9906)
			(end 0.2794 -0.1016)
			(stroke
				(width 0.1)
				(type default)
			)
			(layer "F.Fab")
		)
		(fp_line
			(start -0.2794 -0.1016)
			(end -0.2794 0.9906)
			(stroke
				(width 0.1)
				(type default)
			)
			(layer "F.Fab")
		)
		(fp_line
			(start 0.2794 -0.1016)
			(end -0.2794 -0.1016)
			(stroke
				(width 0.1)
				(type default)
			)
			(layer "F.Fab")
		)
		(pad "1" smd rect
			(at 0 0 270)
			(size 0.508 0.508)
			(layers "F.Cu" "F.Mask" "F.Paste")
			(net "P3V3_STBY")
		)
		(pad "2" smd rect
			(at 0 0.889 270)
			(size 0.508 0.508)
			(layers "F.Cu" "F.Mask" "F.Paste")
			(net "FM_RED_LED_ANODE")
		)
		(zone
			(layer "F.Cu")
			(hatch none 0.5)
			(connect_pads
				(clearance 0)
			)
			(min_thickness 0.25)
			(keepout
				(tracks not_allowed)
				(vias allowed)
				(pads allowed)
				(copperpour not_allowed)
				(footprints allowed)
			)
			(placement
				(enabled no)
				(sheetname "")
			)
			(fill
				(thermal_gap 0.5)
				(thermal_bridge_width 0.5)
				(island_removal_mode 0)
			)
			(polygon
				(pts
					(xy 454.9775 -30.734) (xy 454.9775 -30.226) (xy 455.3585 -30.226) (xy 455.3585 -30.734)
				)
			)
		)
		(zone
			(layer "F.Cu")
			(hatch none 0.5)
			(connect_pads
				(clearance 0)
			)
			(min_thickness 0.25)
			(keepout
				(tracks allowed)
				(vias not_allowed)
				(pads allowed)
				(copperpour not_allowed)
				(footprints allowed)
			)
			(placement
				(enabled no)
				(sheetname "")
			)
			(fill
				(thermal_gap 0.5)
				(thermal_bridge_width 0.5)
				(island_removal_mode 0)
			)
			(polygon
				(pts
					(xy 455.3585 -30.734) (xy 455.3585 -30.226) (xy 454.9775 -30.226) (xy 454.9775 -30.734)
				)
			)
		)
	)
	(footprint ""
		(layer "F.Cu")
		(at 102.258368 -84.7598)
		(property "Reference" "C2D6"
			(at 0 0 0)
			(layer "F.SilkS")
			(hide yes)
			(effects
				(font
					(size 1.27 1.27)
				)
			)
		)
		(property "Value" ""
			(at 0 0 0)
			(layer "F.Fab")
			(effects
				(font
					(size 1.27 1.27)
				)
			)
		)
		(duplicate_pad_numbers_are_jumpers no)
		(fp_poly
			(pts
				(xy -0.4953 -0.2032) (xy 0.4953 -0.2032) (xy 0.4953 1.6002) (xy -0.4953 1.6002)
			)
			(stroke
				(width 0)
				(type default)
			)
			(fill no)
			(layer "F.CrtYd")
		)
		(fp_line
			(start -0.4953 -0.2032)
			(end 0.4953 -0.2032)
			(stroke
				(width 0.1)
				(type default)
			)
			(layer "F.Fab")
		)
		(fp_line
			(start -0.4953 1.6002)
			(end -0.4953 -0.2032)
			(stroke
				(width 0.1)
				(type default)
			)
			(layer "F.Fab")
		)
		(fp_line
			(start 0.4953 -0.2032)
			(end 0.4953 1.6002)
			(stroke
				(width 0.1)
				(type default)
			)
			(layer "F.Fab")
		)
		(fp_line
			(start 0.4953 1.6002)
			(end -0.4953 1.6002)
			(stroke
				(width 0.1)
				(type default)
			)
			(layer "F.Fab")
		)
		(pad "1" smd rect
			(at 0 0)
			(size 0.762 0.889)
			(layers "F.Cu" "F.Mask" "F.Paste")
			(net "PVDDQ_KLM")
		)
		(pad "2" smd rect
			(at 0 1.397)
			(size 0.762 0.889)
			(layers "F.Cu" "F.Mask" "F.Paste")
			(net "GND")
		)
		(zone
			(layer "F.Cu")
			(hatch none 0.5)
			(connect_pads
				(clearance 0)
			)
			(min_thickness 0.25)
			(keepout
				(tracks not_allowed)
				(vias allowed)
				(pads allowed)
				(copperpour not_allowed)
				(footprints allowed)
			)
			(placement
				(enabled no)
				(sheetname "")
			)
			(fill
				(thermal_gap 0.5)
				(thermal_bridge_width 0.5)
				(island_removal_mode 0)
			)
			(polygon
				(pts
					(xy 101.877368 -84.3153) (xy 102.639368 -84.3153) (xy 102.639368 -83.8073) (xy 101.877368 -83.8073)
				)
			)
		)
	)
)
